(kicad_pcb
	(version 20260206)
	(generator "pcbnew")
	(generator_version "10.0")
	(general
		(thickness 1.6)
		(legacy_teardrops no)
	)
	(paper "A4")
	(title_block
		(title "03242023_DA0F0TMBIJ0_F0T_Motherboard_J_brd_V01_OCP.brd")
		(comment 1 "Grand Teton / footprints 4026-4032 of 6105")
	)
	(layers
		(0 "F.Cu" signal "TOP")
		(4 "In1.Cu" signal "GND")
		(6 "In2.Cu" signal "IN1")
		(8 "In3.Cu" signal "GND1")
		(10 "In4.Cu" signal "IN2")
		(12 "In5.Cu" signal "GND2")
		(14 "In6.Cu" signal "IN3")
		(16 "In7.Cu" signal "GND3")
		(18 "In8.Cu" signal "VCC")
		(20 "In9.Cu" signal "VCC1")
		(22 "In10.Cu" signal "GND4")
		(24 "In11.Cu" signal "IN4")
		(26 "In12.Cu" signal "GND5")
		(28 "In13.Cu" signal "IN5")
		(30 "In14.Cu" signal "GND6")
		(32 "In15.Cu" signal "IN6")
		(34 "In16.Cu" signal "GND7")
		(2 "B.Cu" signal "BOTTOM")
		(9 "F.Adhes" user "F.Adhesive")
		(11 "B.Adhes" user "B.Adhesive")
		(13 "F.Paste" user "Package Geometry/Pastemask Top")
		(15 "B.Paste" user "Package Geometry/Pastemask Bottom")
		(5 "F.SilkS" user "Ref Des/Silkscreen Top")
		(7 "B.SilkS" user "Ref Des/Silkscreen Bottom")
		(1 "F.Mask" user "Board Geometry/Soldermask Top")
		(3 "B.Mask" user "Board Geometry/Soldermask Bottom")
		(17 "Dwgs.User" user "User.Drawings")
		(19 "Cmts.User" user "User.Comments")
		(21 "Eco1.User" user "User.Eco1")
		(23 "Eco2.User" user "User.Eco2")
		(25 "Edge.Cuts" user "Board Geometry/Outline")
		(27 "Margin" user)
		(31 "F.CrtYd" user "Package Geometry/Place Bound Top")
		(29 "B.CrtYd" user "Package Geometry/Place Bound Bottom")
		(35 "F.Fab" user "Ref Des/Assembly Top")
		(33 "B.Fab" user "Ref Des/Assembly Bottom")
	)
	(footprint ""
		(layer "F.Cu")
		(at 44.169584 -108.047282)
		(property "Reference" "R2843"
			(at 0 0 0)
			(layer "F.SilkS")
			(hide yes)
			(effects
				(font
					(size 1.27 1.27)
				)
			)
		)
		(property "Value" ""
			(at 0 0 0)
			(layer "F.Fab")
			(effects
				(font
					(size 1.27 1.27)
				)
			)
		)
		(duplicate_pad_numbers_are_jumpers no)
		(fp_line
			(start -0.7874 -0.4064)
			(end 0.7874 -0.4064)
			(stroke
				(width 0.1524)
				(type default)
			)
			(layer "F.SilkS")
		)
		(fp_line
			(start -0.7874 0.4064)
			(end -0.7874 -0.4064)
			(stroke
				(width 0.1524)
				(type default)
			)
			(layer "F.SilkS")
		)
		(fp_line
			(start 0.7874 -0.4064)
			(end 0.7874 0.4064)
			(stroke
				(width 0.1524)
				(type default)
			)
			(layer "F.SilkS")
		)
		(fp_line
			(start 0.7874 0.4064)
			(end -0.7874 0.4064)
			(stroke
				(width 0.1524)
				(type default)
			)
			(layer "F.SilkS")
		)
		(fp_line
			(start -0.67945 -0.305054)
			(end -0.12065 -0.305054)
			(stroke
				(width 0.1)
				(type default)
			)
			(layer "F.Fab")
		)
		(fp_line
			(start -0.67945 0.3048)
			(end -0.67945 -0.305054)
			(stroke
				(width 0.1)
				(type default)
			)
			(layer "F.Fab")
		)
		(fp_line
			(start -0.12065 -0.305054)
			(end -0.12065 -0.2794)
			(stroke
				(width 0.1)
				(type default)
			)
			(layer "F.Fab")
		)
		(fp_line
			(start -0.12065 -0.2794)
			(end 0.12065 -0.2794)
			(stroke
				(width 0.1)
				(type default)
			)
			(layer "F.Fab")
		)
		(fp_line
			(start -0.12065 0.2794)
			(end -0.12065 0.3048)
			(stroke
				(width 0.1)
				(type default)
			)
			(layer "F.Fab")
		)
		(fp_line
			(start -0.12065 0.3048)
			(end -0.67945 0.3048)
			(stroke
				(width 0.1)
				(type default)
			)
			(layer "F.Fab")
		)
		(fp_line
			(start 0.120396 0.2794)
			(end -0.12065 0.2794)
			(stroke
				(width 0.1)
				(type default)
			)
			(layer "F.Fab")
		)
		(fp_line
			(start 0.120396 0.3048)
			(end 0.120396 0.2794)
			(stroke
				(width 0.1)
				(type default)
			)
			(layer "F.Fab")
		)
		(fp_line
			(start 0.12065 -0.3048)
			(end 0.67945 -0.3048)
			(stroke
				(width 0.1)
				(type default)
			)
			(layer "F.Fab")
		)
		(fp_line
			(start 0.12065 -0.2794)
			(end 0.12065 -0.3048)
			(stroke
				(width 0.1)
				(type default)
			)
			(layer "F.Fab")
		)
		(fp_line
			(start 0.67945 -0.3048)
			(end 0.67945 0.3048)
			(stroke
				(width 0.1)
				(type default)
			)
			(layer "F.Fab")
		)
		(fp_line
			(start 0.67945 0.3048)
			(end 0.120396 0.3048)
			(stroke
				(width 0.1)
				(type default)
			)
			(layer "F.Fab")
		)
		(pad "1" smd circle
			(at -0.40005 0)
			(size 0 0)
			(layers "F.Cu" "F.Mask" "F.Paste")
			(net "P3V3_ADC")
		)
		(pad "2" smd circle
			(at 0.40005 0)
			(size 0 0)
			(layers "F.Cu" "F.Mask" "F.Paste")
			(net "GND")
		)
	)
	(footprint ""
		(layer "F.Cu")
		(at 488.85729 -470.49817)
		(property "Reference" "U1_BL"
			(at -1.46685 -1.175258 0)
			(unlocked yes)
			(layer "F.SilkS")
			(effects
				(font
					(size 0.7874 0.5842)
					(thickness 0.1524)
				)
				(justify left)
			)
		)
		(property "Value" ""
			(at 0 0 0)
			(layer "F.Fab")
			(effects
				(font
					(size 1.27 1.27)
				)
			)
		)
		(duplicate_pad_numbers_are_jumpers no)
		(pad "1" smd circle
			(at 0 0)
			(size 0.762 0.762)
			(layers "F.Cu" "F.Mask" "F.Paste")
			(net "Net_8488")
		)
	)
	(footprint ""
		(layer "F.Cu")
		(at 430.600104 -140.595858 180)
		(property "Reference" "R2394"
			(at 0 0 180)
			(layer "F.SilkS")
			(hide yes)
			(effects
				(font
					(size 1.27 1.27)
				)
			)
		)
		(property "Value" ""
			(at 0 0 180)
			(layer "F.Fab")
			(effects
				(font
					(size 1.27 1.27)
				)
			)
		)
		(duplicate_pad_numbers_are_jumpers no)
		(fp_line
			(start 0.7874 0.4064)
			(end -0.7874 0.4064)
			(stroke
				(width 0.1524)
				(type default)
			)
			(layer "F.SilkS")
		)
		(fp_line
			(start 0.7874 -0.4064)
			(end 0.7874 0.4064)
			(stroke
				(width 0.1524)
				(type default)
			)
			(layer "F.SilkS")
		)
		(fp_line
			(start -0.7874 0.4064)
			(end -0.7874 -0.4064)
			(stroke
				(width 0.1524)
				(type default)
			)
			(layer "F.SilkS")
		)
		(fp_line
			(start -0.7874 -0.4064)
			(end 0.7874 -0.4064)
			(stroke
				(width 0.1524)
				(type default)
			)
			(layer "F.SilkS")
		)
		(fp_line
			(start 0.67945 0.3048)
			(end 0.120396 0.3048)
			(stroke
				(width 0.1)
				(type default)
			)
			(layer "F.Fab")
		)
		(fp_line
			(start 0.67945 -0.3048)
			(end 0.67945 0.3048)
			(stroke
				(width 0.1)
				(type default)
			)
			(layer "F.Fab")
		)
		(fp_line
			(start 0.12065 -0.2794)
			(end 0.12065 -0.3048)
			(stroke
				(width 0.1)
				(type default)
			)
			(layer "F.Fab")
		)
		(fp_line
			(start 0.12065 -0.3048)
			(end 0.67945 -0.3048)
			(stroke
				(width 0.1)
				(type default)
			)
			(layer "F.Fab")
		)
		(fp_line
			(start 0.120396 0.3048)
			(end 0.120396 0.2794)
			(stroke
				(width 0.1)
				(type default)
			)
			(layer "F.Fab")
		)
		(fp_line
			(start 0.120396 0.2794)
			(end -0.12065 0.2794)
			(stroke
				(width 0.1)
				(type default)
			)
			(layer "F.Fab")
		)
		(fp_line
			(start -0.12065 0.3048)
			(end -0.67945 0.3048)
			(stroke
				(width 0.1)
				(type default)
			)
			(layer "F.Fab")
		)
		(fp_line
			(start -0.12065 0.2794)
			(end -0.12065 0.3048)
			(stroke
				(width 0.1)
				(type default)
			)
			(layer "F.Fab")
		)
		(fp_line
			(start -0.12065 -0.2794)
			(end 0.12065 -0.2794)
			(stroke
				(width 0.1)
				(type default)
			)
			(layer "F.Fab")
		)
		(fp_line
			(start -0.12065 -0.305054)
			(end -0.12065 -0.2794)
			(stroke
				(width 0.1)
				(type default)
			)
			(layer "F.Fab")
		)
		(fp_line
			(start -0.67945 0.3048)
			(end -0.67945 -0.305054)
			(stroke
				(width 0.1)
				(type default)
			)
			(layer "F.Fab")
		)
		(fp_line
			(start -0.67945 -0.305054)
			(end -0.12065 -0.305054)
			(stroke
				(width 0.1)
				(type default)
			)
			(layer "F.Fab")
		)
		(pad "1" smd circle
			(at -0.40005 0 180)
			(size 0 0)
			(layers "F.Cu" "F.Mask" "F.Paste")
			(net "FM_PVCCFA_EHV_CPU0_EN")
		)
		(pad "2" smd circle
			(at 0.40005 0 180)
			(size 0 0)
			(layers "F.Cu" "F.Mask" "F.Paste")
			(net "PVCCFA_EHV_CPU0_EN_R")
		)
	)
	(footprint ""
		(layer "F.Cu")
		(at 210.560158 -102.93604 180)
		(property "Reference" "C2392"
			(at 0 0 180)
			(layer "F.SilkS")
			(hide yes)
			(effects
				(font
					(size 1.27 1.27)
				)
			)
		)
		(property "Value" ""
			(at 0 0 180)
			(layer "F.Fab")
			(effects
				(font
					(size 1.27 1.27)
				)
			)
		)
		(duplicate_pad_numbers_are_jumpers no)
		(fp_line
			(start 0.7874 0.4064)
			(end -0.7874 0.4064)
			(stroke
				(width 0.1524)
				(type default)
			)
			(layer "F.SilkS")
		)
		(fp_line
			(start 0.7874 -0.4064)
			(end 0.7874 0.4064)
			(stroke
				(width 0.1524)
				(type default)
			)
			(layer "F.SilkS")
		)
		(fp_line
			(start -0.7874 0.4064)
			(end -0.7874 -0.4064)
			(stroke
				(width 0.1524)
				(type default)
			)
			(layer "F.SilkS")
		)
		(fp_line
			(start -0.7874 -0.4064)
			(end 0.7874 -0.4064)
			(stroke
				(width 0.1524)
				(type default)
			)
			(layer "F.SilkS")
		)
		(fp_line
			(start 0.67945 0.3048)
			(end 0.120396 0.3048)
			(stroke
				(width 0.1)
				(type default)
			)
			(layer "F.Fab")
		)
		(fp_line
			(start 0.67945 -0.3048)
			(end 0.67945 0.3048)
			(stroke
				(width 0.1)
				(type default)
			)
			(layer "F.Fab")
		)
		(fp_line
			(start 0.12065 -0.2794)
			(end 0.12065 -0.3048)
			(stroke
				(width 0.1)
				(type default)
			)
			(layer "F.Fab")
		)
		(fp_line
			(start 0.12065 -0.3048)
			(end 0.67945 -0.3048)
			(stroke
				(width 0.1)
				(type default)
			)
			(layer "F.Fab")
		)
		(fp_line
			(start 0.120396 0.3048)
			(end 0.120396 0.2794)
			(stroke
				(width 0.1)
				(type default)
			)
			(layer "F.Fab")
		)
		(fp_line
			(start 0.120396 0.2794)
			(end -0.12065 0.2794)
			(stroke
				(width 0.1)
				(type default)
			)
			(layer "F.Fab")
		)
		(fp_line
			(start -0.12065 0.3048)
			(end -0.67945 0.3048)
			(stroke
				(width 0.1)
				(type default)
			)
			(layer "F.Fab")
		)
		(fp_line
			(start -0.12065 0.2794)
			(end -0.12065 0.3048)
			(stroke
				(width 0.1)
				(type default)
			)
			(layer "F.Fab")
		)
		(fp_line
			(start -0.12065 -0.2794)
			(end 0.12065 -0.2794)
			(stroke
				(width 0.1)
				(type default)
			)
			(layer "F.Fab")
		)
		(fp_line
			(start -0.12065 -0.305054)
			(end -0.12065 -0.2794)
			(stroke
				(width 0.1)
				(type default)
			)
			(layer "F.Fab")
		)
		(fp_line
			(start -0.67945 0.3048)
			(end -0.67945 -0.305054)
			(stroke
				(width 0.1)
				(type default)
			)
			(layer "F.Fab")
		)
		(fp_line
			(start -0.67945 -0.305054)
			(end -0.12065 -0.305054)
			(stroke
				(width 0.1)
				(type default)
			)
			(layer "F.Fab")
		)
		(pad "1" smd circle
			(at -0.40005 0 180)
			(size 0 0)
			(layers "F.Cu" "F.Mask" "F.Paste")
			(net "U205_VDD")
		)
		(pad "2" smd circle
			(at 0.40005 0 180)
			(size 0 0)
			(layers "F.Cu" "F.Mask" "F.Paste")
			(net "GND")
		)
	)
	(footprint ""
		(layer "F.Cu")
		(at 179.2224 -94.338648 90)
		(property "Reference" "R4592"
			(at 0 0 90)
			(layer "F.SilkS")
			(hide yes)
			(effects
				(font
					(size 1.27 1.27)
				)
			)
		)
		(property "Value" ""
			(at 0 0 90)
			(layer "F.Fab")
			(effects
				(font
					(size 1.27 1.27)
				)
			)
		)
		(duplicate_pad_numbers_are_jumpers no)
		(fp_line
			(start 0.7874 -0.4064)
			(end 0.7874 0.4064)
			(stroke
				(width 0.1524)
				(type default)
			)
			(layer "F.SilkS")
		)
		(fp_line
			(start -0.7874 -0.4064)
			(end 0.7874 -0.4064)
			(stroke
				(width 0.1524)
				(type default)
			)
			(layer "F.SilkS")
		)
		(fp_line
			(start 0.7874 0.4064)
			(end -0.7874 0.4064)
			(stroke
				(width 0.1524)
				(type default)
			)
			(layer "F.SilkS")
		)
		(fp_line
			(start -0.7874 0.4064)
			(end -0.7874 -0.4064)
			(stroke
				(width 0.1524)
				(type default)
			)
			(layer "F.SilkS")
		)
		(fp_line
			(start -0.12065 -0.305054)
			(end -0.12065 -0.2794)
			(stroke
				(width 0.1)
				(type default)
			)
			(layer "F.Fab")
		)
		(fp_line
			(start -0.67945 -0.305054)
			(end -0.12065 -0.305054)
			(stroke
				(width 0.1)
				(type default)
			)
			(layer "F.Fab")
		)
		(fp_line
			(start 0.67945 -0.3048)
			(end 0.67945 0.3048)
			(stroke
				(width 0.1)
				(type default)
			)
			(layer "F.Fab")
		)
		(fp_line
			(start 0.12065 -0.3048)
			(end 0.67945 -0.3048)
			(stroke
				(width 0.1)
				(type default)
			)
			(layer "F.Fab")
		)
		(fp_line
			(start 0.12065 -0.2794)
			(end 0.12065 -0.3048)
			(stroke
				(width 0.1)
				(type default)
			)
			(layer "F.Fab")
		)
		(fp_line
			(start -0.12065 -0.2794)
			(end 0.12065 -0.2794)
			(stroke
				(width 0.1)
				(type default)
			)
			(layer "F.Fab")
		)
		(fp_line
			(start 0.120396 0.2794)
			(end -0.12065 0.2794)
			(stroke
				(width 0.1)
				(type default)
			)
			(layer "F.Fab")
		)
		(fp_line
			(start -0.12065 0.2794)
			(end -0.12065 0.3048)
			(stroke
				(width 0.1)
				(type default)
			)
			(layer "F.Fab")
		)
		(fp_line
			(start 0.67945 0.3048)
			(end 0.120396 0.3048)
			(stroke
				(width 0.1)
				(type default)
			)
			(layer "F.Fab")
		)
		(fp_line
			(start 0.120396 0.3048)
			(end 0.120396 0.2794)
			(stroke
				(width 0.1)
				(type default)
			)
			(layer "F.Fab")
		)
		(fp_line
			(start -0.12065 0.3048)
			(end -0.67945 0.3048)
			(stroke
				(width 0.1)
				(type default)
			)
			(layer "F.Fab")
		)
		(fp_line
			(start -0.67945 0.3048)
			(end -0.67945 -0.305054)
			(stroke
				(width 0.1)
				(type default)
			)
			(layer "F.Fab")
		)
		(pad "1" smd rect
			(at -0.40005 0 270)
			(size 0.4572 0.508)
			(layers "F.Cu" "F.Mask" "F.Paste")
			(net "FM_BOARD_BMC_SKU_ID3")
		)
		(pad "2" smd rect
			(at 0.40005 0 270)
			(size 0.4572 0.508)
			(layers "F.Cu" "F.Mask" "F.Paste")
			(net "GND")
		)
	)
	(footprint ""
		(layer "F.Cu")
		(at 285.268162 -16.39443)
		(property "Reference" "R4182"
			(at 0 0 0)
			(layer "F.SilkS")
			(hide yes)
			(effects
				(font
					(size 1.27 1.27)
				)
			)
		)
		(property "Value" ""
			(at 0 0 0)
			(layer "F.Fab")
			(effects
				(font
					(size 1.27 1.27)
				)
			)
		)
		(duplicate_pad_numbers_are_jumpers no)
		(fp_line
			(start -0.7874 -0.4064)
			(end 0.7874 -0.4064)
			(stroke
				(width 0.1524)
				(type default)
			)
			(layer "F.SilkS")
		)
		(fp_line
			(start -0.7874 0.4064)
			(end -0.7874 -0.4064)
			(stroke
				(width 0.1524)
				(type default)
			)
			(layer "F.SilkS")
		)
		(fp_line
			(start 0.7874 -0.4064)
			(end 0.7874 0.4064)
			(stroke
				(width 0.1524)
				(type default)
			)
			(layer "F.SilkS")
		)
		(fp_line
			(start 0.7874 0.4064)
			(end -0.7874 0.4064)
			(stroke
				(width 0.1524)
				(type default)
			)
			(layer "F.SilkS")
		)
		(fp_line
			(start -0.67945 -0.305054)
			(end -0.12065 -0.305054)
			(stroke
				(width 0.1)
				(type default)
			)
			(layer "F.Fab")
		)
		(fp_line
			(start -0.67945 0.3048)
			(end -0.67945 -0.305054)
			(stroke
				(width 0.1)
				(type default)
			)
			(layer "F.Fab")
		)
		(fp_line
			(start -0.12065 -0.305054)
			(end -0.12065 -0.2794)
			(stroke
				(width 0.1)
				(type default)
			)
			(layer "F.Fab")
		)
		(fp_line
			(start -0.12065 -0.2794)
			(end 0.12065 -0.2794)
			(stroke
				(width 0.1)
				(type default)
			)
			(layer "F.Fab")
		)
		(fp_line
			(start -0.12065 0.2794)
			(end -0.12065 0.3048)
			(stroke
				(width 0.1)
				(type default)
			)
			(layer "F.Fab")
		)
		(fp_line
			(start -0.12065 0.3048)
			(end -0.67945 0.3048)
			(stroke
				(width 0.1)
				(type default)
			)
			(layer "F.Fab")
		)
		(fp_line
			(start 0.120396 0.2794)
			(end -0.12065 0.2794)
			(stroke
				(width 0.1)
				(type default)
			)
			(layer "F.Fab")
		)
		(fp_line
			(start 0.120396 0.3048)
			(end 0.120396 0.2794)
			(stroke
				(width 0.1)
				(type default)
			)
			(layer "F.Fab")
		)
		(fp_line
			(start 0.12065 -0.3048)
			(end 0.67945 -0.3048)
			(stroke
				(width 0.1)
				(type default)
			)
			(layer "F.Fab")
		)
		(fp_line
			(start 0.12065 -0.2794)
			(end 0.12065 -0.3048)
			(stroke
				(width 0.1)
				(type default)
			)
			(layer "F.Fab")
		)
		(fp_line
			(start 0.67945 -0.3048)
			(end 0.67945 0.3048)
			(stroke
				(width 0.1)
				(type default)
			)
			(layer "F.Fab")
		)
		(fp_line
			(start 0.67945 0.3048)
			(end 0.120396 0.3048)
			(stroke
				(width 0.1)
				(type default)
			)
			(layer "F.Fab")
		)
		(pad "1" smd circle
			(at -0.40005 0)
			(size 0 0)
			(layers "F.Cu" "F.Mask" "F.Paste")
			(net "SMB_LM75_1_3V3AUX_SDA")
		)
		(pad "2" smd circle
			(at 0.40005 0)
			(size 0 0)
			(layers "F.Cu" "F.Mask" "F.Paste")
			(net "SMB_LM75_1_3V3AUX_SDA_R1")
		)
	)
	(footprint ""
		(layer "F.Cu")
		(at 119.508016 -244.032024 90)
		(property "Reference" "C239"
			(at 0 0 90)
			(layer "F.SilkS")
			(hide yes)
			(effects
				(font
					(size 1.27 1.27)
				)
			)
		)
		(property "Value" ""
			(at 0 0 90)
			(layer "F.Fab")
			(effects
				(font
					(size 1.27 1.27)
				)
			)
		)
		(duplicate_pad_numbers_are_jumpers no)
		(fp_line
			(start 0.7874 -0.4064)
			(end 0.7874 0.4064)
			(stroke
				(width 0.1524)
				(type default)
			)
			(layer "F.SilkS")
		)
		(fp_line
			(start -0.7874 -0.4064)
			(end 0.7874 -0.4064)
			(stroke
				(width 0.1524)
				(type default)
			)
			(layer "F.SilkS")
		)
		(fp_line
			(start 0.7874 0.4064)
			(end -0.7874 0.4064)
			(stroke
				(width 0.1524)
				(type default)
			)
			(layer "F.SilkS")
		)
		(fp_line
			(start -0.7874 0.4064)
			(end -0.7874 -0.4064)
			(stroke
				(width 0.1524)
				(type default)
			)
			(layer "F.SilkS")
		)
		(fp_line
			(start -0.12065 -0.305054)
			(end -0.12065 -0.2794)
			(stroke
				(width 0.1)
				(type default)
			)
			(layer "F.Fab")
		)
		(fp_line
			(start -0.67945 -0.305054)
			(end -0.12065 -0.305054)
			(stroke
				(width 0.1)
				(type default)
			)
			(layer "F.Fab")
		)
		(fp_line
			(start 0.67945 -0.3048)
			(end 0.67945 0.3048)
			(stroke
				(width 0.1)
				(type default)
			)
			(layer "F.Fab")
		)
		(fp_line
			(start 0.12065 -0.3048)
			(end 0.67945 -0.3048)
			(stroke
				(width 0.1)
				(type default)
			)
			(layer "F.Fab")
		)
		(fp_line
			(start 0.12065 -0.2794)
			(end 0.12065 -0.3048)
			(stroke
				(width 0.1)
				(type default)
			)
			(layer "F.Fab")
		)
		(fp_line
			(start -0.12065 -0.2794)
			(end 0.12065 -0.2794)
			(stroke
				(width 0.1)
				(type default)
			)
			(layer "F.Fab")
		)
		(fp_line
			(start 0.120396 0.2794)
			(end -0.12065 0.2794)
			(stroke
				(width 0.1)
				(type default)
			)
			(layer "F.Fab")
		)
		(fp_line
			(start -0.12065 0.2794)
			(end -0.12065 0.3048)
			(stroke
				(width 0.1)
				(type default)
			)
			(layer "F.Fab")
		)
		(fp_line
			(start 0.67945 0.3048)
			(end 0.120396 0.3048)
			(stroke
				(width 0.1)
				(type default)
			)
			(layer "F.Fab")
		)
		(fp_line
			(start 0.120396 0.3048)
			(end 0.120396 0.2794)
			(stroke
				(width 0.1)
				(type default)
			)
			(layer "F.Fab")
		)
		(fp_line
			(start -0.12065 0.3048)
			(end -0.67945 0.3048)
			(stroke
				(width 0.1)
				(type default)
			)
			(layer "F.Fab")
		)
		(fp_line
			(start -0.67945 0.3048)
			(end -0.67945 -0.305054)
			(stroke
				(width 0.1)
				(type default)
			)
			(layer "F.Fab")
		)
		(pad "1" smd circle
			(at -0.40005 0 90)
			(size 0 0)
			(layers "F.Cu" "F.Mask" "F.Paste")
			(net "PVCCIN_CPU1")
		)
		(pad "2" smd circle
			(at 0.40005 0 90)
			(size 0 0)
			(layers "F.Cu" "F.Mask" "F.Paste")
			(net "GND")
		)
	)
)
